(kicad_pcb
	(version 20260206)
	(generator "pcbnew")
	(generator_version "10.0")
	(general
		(thickness 1.6)
		(legacy_teardrops no)
	)
	(paper "A4")
	(title_block
		(title "Bryce Canyon_F.DPB_16315-1-OCP.brd")
		(comment 1 "Bryce Canyon / footprint 2183 of 2223 (IO2), pads 82-95 of 202")
	)
	(layers
		(0 "F.Cu" signal "TOP")
		(4 "In1.Cu" signal "L2GND")
		(6 "In2.Cu" signal "L3")
		(8 "In3.Cu" signal "L4GND")
		(10 "In4.Cu" signal "L5")
		(12 "In5.Cu" signal "L6VCC")
		(14 "In6.Cu" signal "L7VCC")
		(16 "In7.Cu" signal "L8")
		(18 "In8.Cu" signal "L9GND")
		(20 "In9.Cu" signal "L10")
		(22 "In10.Cu" signal "L11GND")
		(2 "B.Cu" signal "BOTTOM")
		(9 "F.Adhes" user "F.Adhesive")
		(11 "B.Adhes" user "B.Adhesive")
		(13 "F.Paste" user "Package Geometry/Pastemask Top")
		(15 "B.Paste" user "Package Geometry/Pastemask Bottom")
		(5 "F.SilkS" user "Ref Des/Silkscreen Top")
		(7 "B.SilkS" user "Ref Des/Silkscreen Bottom")
		(1 "F.Mask" user "Board Geometry/Soldermask Top")
		(3 "B.Mask" user "Board Geometry/Soldermask Bottom")
		(17 "Dwgs.User" user "User.Drawings")
		(19 "Cmts.User" user "User.Comments")
		(21 "Eco1.User" user "User.Eco1")
		(23 "Eco2.User" user "User.Eco2")
		(25 "Edge.Cuts" user "Board Geometry/Outline")
		(27 "Margin" user)
		(31 "F.CrtYd" user "Package Geometry/Place Bound Top")
		(29 "B.CrtYd" user "Package Geometry/Place Bound Bottom")
		(35 "F.Fab" user "Ref Des/Assembly Top")
		(33 "B.Fab" user "Ref Des/Assembly Bottom")
	)
	(footprint ""
		(layer "B.Cu")
		(at 389.349996 -30.550104 180)
		(property "Reference" "IO2"
			(at 0 0 0)
			(layer "B.SilkS")
			(hide yes)
			(effects
				(font
					(size 1.27 1.27)
				)
				(justify mirror)
			)
		)
		(property "Value" "DM-AMP-CONN200-13R-6-GP-01"
			(at 47.5488 -16.5862 180)
			(unlocked yes)
			(layer "B.Fab")
			(hide yes)
			(effects
				(font
					(size 1.016 1.016)
					(thickness 0.1524)
				)
				(justify mirror)
			)
		)
		(property "Device Type" "DMFIT-200P-384346H577-01"
			(at 47.5488 -18.1102 180)
			(unlocked yes)
			(layer "B.Fab")
			(hide yes)
			(effects
				(font
					(size 1.016 1.016)
					(thickness 0.1524)
				)
				(justify mirror)
			)
		)
		(duplicate_pad_numbers_are_jumpers no)
		(pad "E16" thru_hole circle
			(at 34.200084 -8.199882)
			(size 0.664718 0.664718)
			(drill 0.359918)
			(layers "*.Cu" "*.Mask")
			(remove_unused_layers no)
			(net "PCIE_IOM_B_TO_COMP_B_16_DN")
			(clearance 0.264414)
			(padstack
				(mode custom)
				(layer "In1.Cu"
					(shape circle)
					(size 0.664718 0.664718)
					(clearance 0.264414)
				)
				(layer "In2.Cu"
					(shape circle)
					(size 0.664718 0.664718)
					(clearance 0.264414)
				)
				(layer "In3.Cu"
					(shape circle)
					(size 0.664718 0.664718)
					(clearance 0.264414)
				)
				(layer "In4.Cu"
					(shape circle)
					(size 0.664718 0.664718)
					(clearance 0.264414)
				)
				(layer "In5.Cu"
					(shape circle)
					(size 0.664718 0.664718)
					(clearance 0.264414)
				)
				(layer "In6.Cu"
					(shape circle)
					(size 0.762 0.762)
					(clearance 0.1651)
				)
				(layer "In7.Cu"
					(shape circle)
					(size 0.762 0.762)
					(clearance 0.1651)
				)
				(layer "In8.Cu"
					(shape circle)
					(size 0.762 0.762)
					(clearance 0.1651)
				)
				(layer "In9.Cu"
					(shape circle)
					(size 0.762 0.762)
					(clearance 0.1651)
				)
				(layer "In10.Cu"
					(shape circle)
					(size 0.762 0.762)
					(clearance 0.1651)
				)
				(layer "B.Cu"
					(shape circle)
					(size 0.762 0.762)
					(thermal_gap 0.1651)
					(clearance 0.1651)
				)
			)
		)
		(pad "F1" thru_hole circle
			(at 0 -8.599932)
			(size 0.664718 0.664718)
			(drill 0.359918)
			(layers "*.Cu" "*.Mask")
			(remove_unused_layers no)
			(net "PCIE_IOM_B_TO_COMP_B_8_DP")
			(clearance 0.264414)
			(padstack
				(mode custom)
				(layer "In1.Cu"
					(shape circle)
					(size 0.664718 0.664718)
					(clearance 0.264414)
				)
				(layer "In2.Cu"
					(shape circle)
					(size 0.664718 0.664718)
					(clearance 0.264414)
				)
				(layer "In3.Cu"
					(shape circle)
					(size 0.664718 0.664718)
					(clearance 0.264414)
				)
				(layer "In4.Cu"
					(shape circle)
					(size 0.664718 0.664718)
					(clearance 0.264414)
				)
				(layer "In5.Cu"
					(shape circle)
					(size 0.664718 0.664718)
					(clearance 0.264414)
				)
				(layer "In6.Cu"
					(shape circle)
					(size 0.762 0.762)
					(clearance 0.1651)
				)
				(layer "In7.Cu"
					(shape circle)
					(size 0.762 0.762)
					(clearance 0.1651)
				)
				(layer "In8.Cu"
					(shape circle)
					(size 0.762 0.762)
					(clearance 0.1651)
				)
				(layer "In9.Cu"
					(shape circle)
					(size 0.762 0.762)
					(clearance 0.1651)
				)
				(layer "In10.Cu"
					(shape circle)
					(size 0.762 0.762)
					(clearance 0.1651)
				)
				(layer "B.Cu"
					(shape circle)
					(size 0.762 0.762)
					(thermal_gap 0.1651)
					(clearance 0.1651)
				)
			)
		)
		(pad "F2" thru_hole circle
			(at 1.800098 -9.59993)
			(size 0.664718 0.664718)
			(drill 0.359918)
			(layers "*.Cu" "*.Mask")
			(remove_unused_layers no)
			(net "PCIE_IOM_B_TO_COMP_B_9_DP")
			(clearance 0.264414)
			(padstack
				(mode custom)
				(layer "In1.Cu"
					(shape circle)
					(size 0.664718 0.664718)
					(clearance 0.264414)
				)
				(layer "In2.Cu"
					(shape circle)
					(size 0.664718 0.664718)
					(clearance 0.264414)
				)
				(layer "In3.Cu"
					(shape circle)
					(size 0.664718 0.664718)
					(clearance 0.264414)
				)
				(layer "In4.Cu"
					(shape circle)
					(size 0.664718 0.664718)
					(clearance 0.264414)
				)
				(layer "In5.Cu"
					(shape circle)
					(size 0.664718 0.664718)
					(clearance 0.264414)
				)
				(layer "In6.Cu"
					(shape circle)
					(size 0.762 0.762)
					(clearance 0.1651)
				)
				(layer "In7.Cu"
					(shape circle)
					(size 0.762 0.762)
					(clearance 0.1651)
				)
				(layer "In8.Cu"
					(shape circle)
					(size 0.762 0.762)
					(clearance 0.1651)
				)
				(layer "In9.Cu"
					(shape circle)
					(size 0.762 0.762)
					(clearance 0.1651)
				)
				(layer "In10.Cu"
					(shape circle)
					(size 0.762 0.762)
					(clearance 0.1651)
				)
				(layer "B.Cu"
					(shape circle)
					(size 0.762 0.762)
					(thermal_gap 0.1651)
					(clearance 0.1651)
				)
			)
		)
		(pad "F3" thru_hole circle
			(at 3.599942 -8.599932)
			(size 0.664718 0.664718)
			(drill 0.359918)
			(layers "*.Cu" "*.Mask")
			(remove_unused_layers no)
			(net "PCIE_IOM_B_TO_COMP_B_10_DP")
			(clearance 0.264414)
			(padstack
				(mode custom)
				(layer "In1.Cu"
					(shape circle)
					(size 0.664718 0.664718)
					(clearance 0.264414)
				)
				(layer "In2.Cu"
					(shape circle)
					(size 0.664718 0.664718)
					(clearance 0.264414)
				)
				(layer "In3.Cu"
					(shape circle)
					(size 0.664718 0.664718)
					(clearance 0.264414)
				)
				(layer "In4.Cu"
					(shape circle)
					(size 0.664718 0.664718)
					(clearance 0.264414)
				)
				(layer "In5.Cu"
					(shape circle)
					(size 0.664718 0.664718)
					(clearance 0.264414)
				)
				(layer "In6.Cu"
					(shape circle)
					(size 0.762 0.762)
					(clearance 0.1651)
				)
				(layer "In7.Cu"
					(shape circle)
					(size 0.762 0.762)
					(clearance 0.1651)
				)
				(layer "In8.Cu"
					(shape circle)
					(size 0.762 0.762)
					(clearance 0.1651)
				)
				(layer "In9.Cu"
					(shape circle)
					(size 0.762 0.762)
					(clearance 0.1651)
				)
				(layer "In10.Cu"
					(shape circle)
					(size 0.762 0.762)
					(clearance 0.1651)
				)
				(layer "B.Cu"
					(shape circle)
					(size 0.762 0.762)
					(thermal_gap 0.1651)
					(clearance 0.1651)
				)
			)
		)
		(pad "F4" thru_hole circle
			(at 5.40004 -9.59993)
			(size 0.664718 0.664718)
			(drill 0.359918)
			(layers "*.Cu" "*.Mask")
			(remove_unused_layers no)
			(net "PCIE_IOM_B_TO_COMP_B_11_DP")
			(clearance 0.264414)
			(padstack
				(mode custom)
				(layer "In1.Cu"
					(shape circle)
					(size 0.664718 0.664718)
					(clearance 0.264414)
				)
				(layer "In2.Cu"
					(shape circle)
					(size 0.664718 0.664718)
					(clearance 0.264414)
				)
				(layer "In3.Cu"
					(shape circle)
					(size 0.664718 0.664718)
					(clearance 0.264414)
				)
				(layer "In4.Cu"
					(shape circle)
					(size 0.664718 0.664718)
					(clearance 0.264414)
				)
				(layer "In5.Cu"
					(shape circle)
					(size 0.664718 0.664718)
					(clearance 0.264414)
				)
				(layer "In6.Cu"
					(shape circle)
					(size 0.762 0.762)
					(clearance 0.1651)
				)
				(layer "In7.Cu"
					(shape circle)
					(size 0.762 0.762)
					(clearance 0.1651)
				)
				(layer "In8.Cu"
					(shape circle)
					(size 0.762 0.762)
					(clearance 0.1651)
				)
				(layer "In9.Cu"
					(shape circle)
					(size 0.762 0.762)
					(clearance 0.1651)
				)
				(layer "In10.Cu"
					(shape circle)
					(size 0.762 0.762)
					(clearance 0.1651)
				)
				(layer "B.Cu"
					(shape circle)
					(size 0.762 0.762)
					(thermal_gap 0.1651)
					(clearance 0.1651)
				)
			)
		)
		(pad "F5" thru_hole circle
			(at 7.199884 -8.599932)
			(size 0.664718 0.664718)
			(drill 0.359918)
			(layers "*.Cu" "*.Mask")
			(remove_unused_layers no)
			(net "PCIE_IOM_B_TO_COMP_B_12_DP")
			(clearance 0.264414)
			(padstack
				(mode custom)
				(layer "In1.Cu"
					(shape circle)
					(size 0.664718 0.664718)
					(clearance 0.264414)
				)
				(layer "In2.Cu"
					(shape circle)
					(size 0.664718 0.664718)
					(clearance 0.264414)
				)
				(layer "In3.Cu"
					(shape circle)
					(size 0.664718 0.664718)
					(clearance 0.264414)
				)
				(layer "In4.Cu"
					(shape circle)
					(size 0.664718 0.664718)
					(clearance 0.264414)
				)
				(layer "In5.Cu"
					(shape circle)
					(size 0.664718 0.664718)
					(clearance 0.264414)
				)
				(layer "In6.Cu"
					(shape circle)
					(size 0.762 0.762)
					(clearance 0.1651)
				)
				(layer "In7.Cu"
					(shape circle)
					(size 0.762 0.762)
					(clearance 0.1651)
				)
				(layer "In8.Cu"
					(shape circle)
					(size 0.762 0.762)
					(clearance 0.1651)
				)
				(layer "In9.Cu"
					(shape circle)
					(size 0.762 0.762)
					(clearance 0.1651)
				)
				(layer "In10.Cu"
					(shape circle)
					(size 0.762 0.762)
					(clearance 0.1651)
				)
				(layer "B.Cu"
					(shape circle)
					(size 0.762 0.762)
					(thermal_gap 0.1651)
					(clearance 0.1651)
				)
			)
		)
		(pad "F6" thru_hole circle
			(at 8.999982 -9.59993)
			(size 0.664718 0.664718)
			(drill 0.359918)
			(layers "*.Cu" "*.Mask")
			(remove_unused_layers no)
			(net "PCIE_IOM_B_TO_COMP_B_13_DP")
			(clearance 0.264414)
			(padstack
				(mode custom)
				(layer "In1.Cu"
					(shape circle)
					(size 0.664718 0.664718)
					(clearance 0.264414)
				)
				(layer "In2.Cu"
					(shape circle)
					(size 0.664718 0.664718)
					(clearance 0.264414)
				)
				(layer "In3.Cu"
					(shape circle)
					(size 0.664718 0.664718)
					(clearance 0.264414)
				)
				(layer "In4.Cu"
					(shape circle)
					(size 0.664718 0.664718)
					(clearance 0.264414)
				)
				(layer "In5.Cu"
					(shape circle)
					(size 0.664718 0.664718)
					(clearance 0.264414)
				)
				(layer "In6.Cu"
					(shape circle)
					(size 0.762 0.762)
					(clearance 0.1651)
				)
				(layer "In7.Cu"
					(shape circle)
					(size 0.762 0.762)
					(clearance 0.1651)
				)
				(layer "In8.Cu"
					(shape circle)
					(size 0.762 0.762)
					(clearance 0.1651)
				)
				(layer "In9.Cu"
					(shape circle)
					(size 0.762 0.762)
					(clearance 0.1651)
				)
				(layer "In10.Cu"
					(shape circle)
					(size 0.762 0.762)
					(clearance 0.1651)
				)
				(layer "B.Cu"
					(shape circle)
					(size 0.762 0.762)
					(thermal_gap 0.1651)
					(clearance 0.1651)
				)
			)
		)
		(pad "F7" thru_hole circle
			(at 10.80008 -8.599932)
			(size 0.664718 0.664718)
			(drill 0.359918)
			(layers "*.Cu" "*.Mask")
			(remove_unused_layers no)
			(net "PCIE_IOM_B_TO_COMP_B_14_DP")
			(clearance 0.264414)
			(padstack
				(mode custom)
				(layer "In1.Cu"
					(shape circle)
					(size 0.664718 0.664718)
					(clearance 0.264414)
				)
				(layer "In2.Cu"
					(shape circle)
					(size 0.664718 0.664718)
					(clearance 0.264414)
				)
				(layer "In3.Cu"
					(shape circle)
					(size 0.664718 0.664718)
					(clearance 0.264414)
				)
				(layer "In4.Cu"
					(shape circle)
					(size 0.664718 0.664718)
					(clearance 0.264414)
				)
				(layer "In5.Cu"
					(shape circle)
					(size 0.664718 0.664718)
					(clearance 0.264414)
				)
				(layer "In6.Cu"
					(shape circle)
					(size 0.762 0.762)
					(clearance 0.1651)
				)
				(layer "In7.Cu"
					(shape circle)
					(size 0.762 0.762)
					(clearance 0.1651)
				)
				(layer "In8.Cu"
					(shape circle)
					(size 0.762 0.762)
					(clearance 0.1651)
				)
				(layer "In9.Cu"
					(shape circle)
					(size 0.762 0.762)
					(clearance 0.1651)
				)
				(layer "In10.Cu"
					(shape circle)
					(size 0.762 0.762)
					(clearance 0.1651)
				)
				(layer "B.Cu"
					(shape circle)
					(size 0.762 0.762)
					(thermal_gap 0.1651)
					(clearance 0.1651)
				)
			)
		)
		(pad "F8" thru_hole circle
			(at 12.599924 -9.59993)
			(size 0.664718 0.664718)
			(drill 0.359918)
			(layers "*.Cu" "*.Mask")
			(remove_unused_layers no)
			(net "PCIE_IOM_B_TO_COMP_B_15_DP")
			(clearance 0.264414)
			(padstack
				(mode custom)
				(layer "In1.Cu"
					(shape circle)
					(size 0.664718 0.664718)
					(clearance 0.264414)
				)
				(layer "In2.Cu"
					(shape circle)
					(size 0.664718 0.664718)
					(clearance 0.264414)
				)
				(layer "In3.Cu"
					(shape circle)
					(size 0.664718 0.664718)
					(clearance 0.264414)
				)
				(layer "In4.Cu"
					(shape circle)
					(size 0.664718 0.664718)
					(clearance 0.264414)
				)
				(layer "In5.Cu"
					(shape circle)
					(size 0.664718 0.664718)
					(clearance 0.264414)
				)
				(layer "In6.Cu"
					(shape circle)
					(size 0.762 0.762)
					(clearance 0.1651)
				)
				(layer "In7.Cu"
					(shape circle)
					(size 0.762 0.762)
					(clearance 0.1651)
				)
				(layer "In8.Cu"
					(shape circle)
					(size 0.762 0.762)
					(clearance 0.1651)
				)
				(layer "In9.Cu"
					(shape circle)
					(size 0.762 0.762)
					(clearance 0.1651)
				)
				(layer "In10.Cu"
					(shape circle)
					(size 0.762 0.762)
					(clearance 0.1651)
				)
				(layer "B.Cu"
					(shape circle)
					(size 0.762 0.762)
					(thermal_gap 0.1651)
					(clearance 0.1651)
				)
			)
		)
		(pad "F9" thru_hole circle
			(at 21.599906 -8.599932)
			(size 0.664718 0.664718)
			(drill 0.359918)
			(layers "*.Cu" "*.Mask")
			(remove_unused_layers no)
			(net "PCIE_IOM_B_TO_COMP_B_23_DP")
			(clearance 0.264414)
			(padstack
				(mode custom)
				(layer "In1.Cu"
					(shape circle)
					(size 0.664718 0.664718)
					(clearance 0.264414)
				)
				(layer "In2.Cu"
					(shape circle)
					(size 0.664718 0.664718)
					(clearance 0.264414)
				)
				(layer "In3.Cu"
					(shape circle)
					(size 0.664718 0.664718)
					(clearance 0.264414)
				)
				(layer "In4.Cu"
					(shape circle)
					(size 0.664718 0.664718)
					(clearance 0.264414)
				)
				(layer "In5.Cu"
					(shape circle)
					(size 0.664718 0.664718)
					(clearance 0.264414)
				)
				(layer "In6.Cu"
					(shape circle)
					(size 0.762 0.762)
					(clearance 0.1651)
				)
				(layer "In7.Cu"
					(shape circle)
					(size 0.762 0.762)
					(clearance 0.1651)
				)
				(layer "In8.Cu"
					(shape circle)
					(size 0.762 0.762)
					(clearance 0.1651)
				)
				(layer "In9.Cu"
					(shape circle)
					(size 0.762 0.762)
					(clearance 0.1651)
				)
				(layer "In10.Cu"
					(shape circle)
					(size 0.762 0.762)
					(clearance 0.1651)
				)
				(layer "B.Cu"
					(shape circle)
					(size 0.762 0.762)
					(thermal_gap 0.1651)
					(clearance 0.1651)
				)
			)
		)
		(pad "F10" thru_hole circle
			(at 23.400004 -9.59993)
			(size 0.664718 0.664718)
			(drill 0.359918)
			(layers "*.Cu" "*.Mask")
			(remove_unused_layers no)
			(net "PCIE_IOM_B_TO_COMP_B_22_DP")
			(clearance 0.264414)
			(padstack
				(mode custom)
				(layer "In1.Cu"
					(shape circle)
					(size 0.664718 0.664718)
					(clearance 0.264414)
				)
				(layer "In2.Cu"
					(shape circle)
					(size 0.664718 0.664718)
					(clearance 0.264414)
				)
				(layer "In3.Cu"
					(shape circle)
					(size 0.664718 0.664718)
					(clearance 0.264414)
				)
				(layer "In4.Cu"
					(shape circle)
					(size 0.664718 0.664718)
					(clearance 0.264414)
				)
				(layer "In5.Cu"
					(shape circle)
					(size 0.664718 0.664718)
					(clearance 0.264414)
				)
				(layer "In6.Cu"
					(shape circle)
					(size 0.762 0.762)
					(clearance 0.1651)
				)
				(layer "In7.Cu"
					(shape circle)
					(size 0.762 0.762)
					(clearance 0.1651)
				)
				(layer "In8.Cu"
					(shape circle)
					(size 0.762 0.762)
					(clearance 0.1651)
				)
				(layer "In9.Cu"
					(shape circle)
					(size 0.762 0.762)
					(clearance 0.1651)
				)
				(layer "In10.Cu"
					(shape circle)
					(size 0.762 0.762)
					(clearance 0.1651)
				)
				(layer "B.Cu"
					(shape circle)
					(size 0.762 0.762)
					(thermal_gap 0.1651)
					(clearance 0.1651)
				)
			)
		)
		(pad "F11" thru_hole circle
			(at 25.200102 -8.599932)
			(size 0.664718 0.664718)
			(drill 0.359918)
			(layers "*.Cu" "*.Mask")
			(remove_unused_layers no)
			(net "PCIE_IOM_B_TO_COMP_B_21_DP")
			(clearance 0.264414)
			(padstack
				(mode custom)
				(layer "In1.Cu"
					(shape circle)
					(size 0.664718 0.664718)
					(clearance 0.264414)
				)
				(layer "In2.Cu"
					(shape circle)
					(size 0.664718 0.664718)
					(clearance 0.264414)
				)
				(layer "In3.Cu"
					(shape circle)
					(size 0.664718 0.664718)
					(clearance 0.264414)
				)
				(layer "In4.Cu"
					(shape circle)
					(size 0.664718 0.664718)
					(clearance 0.264414)
				)
				(layer "In5.Cu"
					(shape circle)
					(size 0.664718 0.664718)
					(clearance 0.264414)
				)
				(layer "In6.Cu"
					(shape circle)
					(size 0.762 0.762)
					(clearance 0.1651)
				)
				(layer "In7.Cu"
					(shape circle)
					(size 0.762 0.762)
					(clearance 0.1651)
				)
				(layer "In8.Cu"
					(shape circle)
					(size 0.762 0.762)
					(clearance 0.1651)
				)
				(layer "In9.Cu"
					(shape circle)
					(size 0.762 0.762)
					(clearance 0.1651)
				)
				(layer "In10.Cu"
					(shape circle)
					(size 0.762 0.762)
					(clearance 0.1651)
				)
				(layer "B.Cu"
					(shape circle)
					(size 0.762 0.762)
					(thermal_gap 0.1651)
					(clearance 0.1651)
				)
			)
		)
		(pad "F12" thru_hole circle
			(at 26.999946 -9.59993)
			(size 0.664718 0.664718)
			(drill 0.359918)
			(layers "*.Cu" "*.Mask")
			(remove_unused_layers no)
			(net "PCIE_IOM_B_TO_COMP_B_20_DP")
			(clearance 0.264414)
			(padstack
				(mode custom)
				(layer "In1.Cu"
					(shape circle)
					(size 0.664718 0.664718)
					(clearance 0.264414)
				)
				(layer "In2.Cu"
					(shape circle)
					(size 0.664718 0.664718)
					(clearance 0.264414)
				)
				(layer "In3.Cu"
					(shape circle)
					(size 0.664718 0.664718)
					(clearance 0.264414)
				)
				(layer "In4.Cu"
					(shape circle)
					(size 0.664718 0.664718)
					(clearance 0.264414)
				)
				(layer "In5.Cu"
					(shape circle)
					(size 0.664718 0.664718)
					(clearance 0.264414)
				)
				(layer "In6.Cu"
					(shape circle)
					(size 0.762 0.762)
					(clearance 0.1651)
				)
				(layer "In7.Cu"
					(shape circle)
					(size 0.762 0.762)
					(clearance 0.1651)
				)
				(layer "In8.Cu"
					(shape circle)
					(size 0.762 0.762)
					(clearance 0.1651)
				)
				(layer "In9.Cu"
					(shape circle)
					(size 0.762 0.762)
					(clearance 0.1651)
				)
				(layer "In10.Cu"
					(shape circle)
					(size 0.762 0.762)
					(clearance 0.1651)
				)
				(layer "B.Cu"
					(shape circle)
					(size 0.762 0.762)
					(thermal_gap 0.1651)
					(clearance 0.1651)
				)
			)
		)
		(pad "F13" thru_hole circle
			(at 28.800044 -8.599932)
			(size 0.664718 0.664718)
			(drill 0.359918)
			(layers "*.Cu" "*.Mask")
			(remove_unused_layers no)
			(net "PCIE_IOM_B_TO_COMP_B_19_DP")
			(clearance 0.264414)
			(padstack
				(mode custom)
				(layer "In1.Cu"
					(shape circle)
					(size 0.664718 0.664718)
					(clearance 0.264414)
				)
				(layer "In2.Cu"
					(shape circle)
					(size 0.664718 0.664718)
					(clearance 0.264414)
				)
				(layer "In3.Cu"
					(shape circle)
					(size 0.664718 0.664718)
					(clearance 0.264414)
				)
				(layer "In4.Cu"
					(shape circle)
					(size 0.664718 0.664718)
					(clearance 0.264414)
				)
				(layer "In5.Cu"
					(shape circle)
					(size 0.664718 0.664718)
					(clearance 0.264414)
				)
				(layer "In6.Cu"
					(shape circle)
					(size 0.762 0.762)
					(clearance 0.1651)
				)
				(layer "In7.Cu"
					(shape circle)
					(size 0.762 0.762)
					(clearance 0.1651)
				)
				(layer "In8.Cu"
					(shape circle)
					(size 0.762 0.762)
					(clearance 0.1651)
				)
				(layer "In9.Cu"
					(shape circle)
					(size 0.762 0.762)
					(clearance 0.1651)
				)
				(layer "In10.Cu"
					(shape circle)
					(size 0.762 0.762)
					(clearance 0.1651)
				)
				(layer "B.Cu"
					(shape circle)
					(size 0.762 0.762)
					(thermal_gap 0.1651)
					(clearance 0.1651)
				)
			)
		)
	)
)
